(kicad_pcb
	(version 20260206)
	(generator "pcbnew")
	(generator_version "10.0")
	(general
		(thickness 1.6)
		(legacy_teardrops no)
	)
	(paper "A4")
	(title_block
		(title "01162023_DA0F0TEBIF0_F0T_Expander_BD_F_brd_V02_OCP.brd")
		(comment 1 "Grand Teton / footprints 438-443 of 9728")
	)
	(layers
		(0 "F.Cu" signal "TOP")
		(4 "In1.Cu" signal "GND")
		(6 "In2.Cu" signal "VCC")
		(8 "In3.Cu" signal "VCC1")
		(10 "In4.Cu" signal "GND1")
		(12 "In5.Cu" signal "IN1")
		(14 "In6.Cu" signal "GND2")
		(16 "In7.Cu" signal "IN2")
		(18 "In8.Cu" signal "GND3")
		(20 "In9.Cu" signal "IN3")
		(22 "In10.Cu" signal "GND4")
		(24 "In11.Cu" signal "IN4")
		(26 "In12.Cu" signal "GND5")
		(28 "In13.Cu" signal "IN5")
		(30 "In14.Cu" signal "GND6")
		(32 "In15.Cu" signal "IN6")
		(34 "In16.Cu" signal "GND7")
		(2 "B.Cu" signal "BOTTOM")
		(9 "F.Adhes" user "F.Adhesive")
		(11 "B.Adhes" user "B.Adhesive")
		(13 "F.Paste" user "Package Geometry/Pastemask Top")
		(15 "B.Paste" user "Package Geometry/Pastemask Bottom")
		(5 "F.SilkS" user "Ref Des/Silkscreen Top")
		(7 "B.SilkS" user "Ref Des/Silkscreen Bottom")
		(1 "F.Mask" user "Board Geometry/Soldermask Top")
		(3 "B.Mask" user "Board Geometry/Soldermask Bottom")
		(17 "Dwgs.User" user "User.Drawings")
		(19 "Cmts.User" user "User.Comments")
		(21 "Eco1.User" user "User.Eco1")
		(23 "Eco2.User" user "User.Eco2")
		(25 "Edge.Cuts" user "Board Geometry/Outline")
		(27 "Margin" user)
		(31 "F.CrtYd" user "Package Geometry/Place Bound Top")
		(29 "B.CrtYd" user "Package Geometry/Place Bound Bottom")
		(35 "F.Fab" user "Ref Des/Assembly Top")
		(33 "B.Fab" user "Ref Des/Assembly Bottom")
	)
	(footprint ""
		(layer "F.Cu")
		(at 338.074 -185.039 180)
		(property "Reference" "R4762"
			(at 0 0 180)
			(layer "F.SilkS")
			(hide yes)
			(effects
				(font
					(size 1.27 1.27)
				)
			)
		)
		(property "Value" ""
			(at 0 0 180)
			(layer "F.Fab")
			(effects
				(font
					(size 1.27 1.27)
				)
			)
		)
		(duplicate_pad_numbers_are_jumpers no)
		(fp_line
			(start 0.7874 0.4064)
			(end -0.7874 0.4064)
			(stroke
				(width 0.1524)
				(type default)
			)
			(layer "F.SilkS")
		)
		(fp_line
			(start 0.7874 -0.4064)
			(end 0.7874 0.4064)
			(stroke
				(width 0.1524)
				(type default)
			)
			(layer "F.SilkS")
		)
		(fp_line
			(start -0.7874 0.4064)
			(end -0.7874 -0.4064)
			(stroke
				(width 0.1524)
				(type default)
			)
			(layer "F.SilkS")
		)
		(fp_line
			(start -0.7874 -0.4064)
			(end 0.7874 -0.4064)
			(stroke
				(width 0.1524)
				(type default)
			)
			(layer "F.SilkS")
		)
		(fp_line
			(start 0.67945 0.3048)
			(end 0.120396 0.3048)
			(stroke
				(width 0.1)
				(type default)
			)
			(layer "F.Fab")
		)
		(fp_line
			(start 0.67945 -0.3048)
			(end 0.67945 0.3048)
			(stroke
				(width 0.1)
				(type default)
			)
			(layer "F.Fab")
		)
		(fp_line
			(start 0.12065 -0.2794)
			(end 0.12065 -0.3048)
			(stroke
				(width 0.1)
				(type default)
			)
			(layer "F.Fab")
		)
		(fp_line
			(start 0.12065 -0.3048)
			(end 0.67945 -0.3048)
			(stroke
				(width 0.1)
				(type default)
			)
			(layer "F.Fab")
		)
		(fp_line
			(start 0.120396 0.3048)
			(end 0.120396 0.2794)
			(stroke
				(width 0.1)
				(type default)
			)
			(layer "F.Fab")
		)
		(fp_line
			(start 0.120396 0.2794)
			(end -0.12065 0.2794)
			(stroke
				(width 0.1)
				(type default)
			)
			(layer "F.Fab")
		)
		(fp_line
			(start -0.12065 0.3048)
			(end -0.67945 0.3048)
			(stroke
				(width 0.1)
				(type default)
			)
			(layer "F.Fab")
		)
		(fp_line
			(start -0.12065 0.2794)
			(end -0.12065 0.3048)
			(stroke
				(width 0.1)
				(type default)
			)
			(layer "F.Fab")
		)
		(fp_line
			(start -0.12065 -0.2794)
			(end 0.12065 -0.2794)
			(stroke
				(width 0.1)
				(type default)
			)
			(layer "F.Fab")
		)
		(fp_line
			(start -0.12065 -0.305054)
			(end -0.12065 -0.2794)
			(stroke
				(width 0.1)
				(type default)
			)
			(layer "F.Fab")
		)
		(fp_line
			(start -0.67945 0.3048)
			(end -0.67945 -0.305054)
			(stroke
				(width 0.1)
				(type default)
			)
			(layer "F.Fab")
		)
		(fp_line
			(start -0.67945 -0.305054)
			(end -0.12065 -0.305054)
			(stroke
				(width 0.1)
				(type default)
			)
			(layer "F.Fab")
		)
		(pad "1" smd circle
			(at -0.40005 0 180)
			(size 0 0)
			(layers "F.Cu" "F.Mask" "F.Paste")
			(net "GND")
		)
		(pad "2" smd circle
			(at 0.40005 0 180)
			(size 0 0)
			(layers "F.Cu" "F.Mask" "F.Paste")
			(net "PCA9555_0_PEX2_A1")
		)
	)
	(footprint ""
		(layer "F.Cu")
		(at 465.766658 -534.632662 180)
		(property "Reference" "SCREW_SSD10_1"
			(at -5.6007 -1.402334 0)
			(unlocked yes)
			(layer "B.SilkS")
			(effects
				(font
					(size 0.7874 0.5842)
					(thickness 0.1524)
				)
				(justify mirror)
			)
		)
		(property "Value" ""
			(at 0 0 180)
			(layer "F.Fab")
			(effects
				(font
					(size 1.27 1.27)
				)
			)
		)
		(duplicate_pad_numbers_are_jumpers no)
		(pad "1" thru_hole circle
			(at 0 0 180)
			(size 0.4572 0.4572)
			(drill 0.2032)
			(layers "*.Cu" "*.Mask")
			(remove_unused_layers no)
			(net "Net_9154")
			(clearance 0.127)
			(thermal_gap 0.127)
			(padstack
				(mode front_inner_back)
				(layer "Inner"
					(shape circle)
					(size 0.4572 0.4572)
					(clearance 0.127)
				)
				(layer "B.Cu"
					(shape circle)
					(size 0.508 0.508)
					(clearance 0.1016)
				)
			)
		)
	)
	(footprint ""
		(layer "F.Cu")
		(at 56.901842 -32.849312 90)
		(property "Reference" "R5662"
			(at 0 0 90)
			(layer "F.SilkS")
			(hide yes)
			(effects
				(font
					(size 1.27 1.27)
				)
			)
		)
		(property "Value" ""
			(at 0 0 90)
			(layer "F.Fab")
			(effects
				(font
					(size 1.27 1.27)
				)
			)
		)
		(duplicate_pad_numbers_are_jumpers no)
		(fp_line
			(start 0.7874 -0.4064)
			(end 0.7874 0.4064)
			(stroke
				(width 0.1524)
				(type default)
			)
			(layer "F.SilkS")
		)
		(fp_line
			(start -0.7874 -0.4064)
			(end 0.7874 -0.4064)
			(stroke
				(width 0.1524)
				(type default)
			)
			(layer "F.SilkS")
		)
		(fp_line
			(start 0.7874 0.4064)
			(end -0.7874 0.4064)
			(stroke
				(width 0.1524)
				(type default)
			)
			(layer "F.SilkS")
		)
		(fp_line
			(start -0.7874 0.4064)
			(end -0.7874 -0.4064)
			(stroke
				(width 0.1524)
				(type default)
			)
			(layer "F.SilkS")
		)
		(fp_line
			(start -0.12065 -0.305054)
			(end -0.12065 -0.2794)
			(stroke
				(width 0.1)
				(type default)
			)
			(layer "F.Fab")
		)
		(fp_line
			(start -0.67945 -0.305054)
			(end -0.12065 -0.305054)
			(stroke
				(width 0.1)
				(type default)
			)
			(layer "F.Fab")
		)
		(fp_line
			(start 0.67945 -0.3048)
			(end 0.67945 0.3048)
			(stroke
				(width 0.1)
				(type default)
			)
			(layer "F.Fab")
		)
		(fp_line
			(start 0.12065 -0.3048)
			(end 0.67945 -0.3048)
			(stroke
				(width 0.1)
				(type default)
			)
			(layer "F.Fab")
		)
		(fp_line
			(start 0.12065 -0.2794)
			(end 0.12065 -0.3048)
			(stroke
				(width 0.1)
				(type default)
			)
			(layer "F.Fab")
		)
		(fp_line
			(start -0.12065 -0.2794)
			(end 0.12065 -0.2794)
			(stroke
				(width 0.1)
				(type default)
			)
			(layer "F.Fab")
		)
		(fp_line
			(start 0.120396 0.2794)
			(end -0.12065 0.2794)
			(stroke
				(width 0.1)
				(type default)
			)
			(layer "F.Fab")
		)
		(fp_line
			(start -0.12065 0.2794)
			(end -0.12065 0.3048)
			(stroke
				(width 0.1)
				(type default)
			)
			(layer "F.Fab")
		)
		(fp_line
			(start 0.67945 0.3048)
			(end 0.120396 0.3048)
			(stroke
				(width 0.1)
				(type default)
			)
			(layer "F.Fab")
		)
		(fp_line
			(start 0.120396 0.3048)
			(end 0.120396 0.2794)
			(stroke
				(width 0.1)
				(type default)
			)
			(layer "F.Fab")
		)
		(fp_line
			(start -0.12065 0.3048)
			(end -0.67945 0.3048)
			(stroke
				(width 0.1)
				(type default)
			)
			(layer "F.Fab")
		)
		(fp_line
			(start -0.67945 0.3048)
			(end -0.67945 -0.305054)
			(stroke
				(width 0.1)
				(type default)
			)
			(layer "F.Fab")
		)
		(pad "1" smd circle
			(at -0.40005 0 90)
			(size 0 0)
			(layers "F.Cu" "F.Mask" "F.Paste")
			(net "RST_SMB_SSD2_ISO_R_N")
		)
		(pad "2" smd circle
			(at 0.40005 0 90)
			(size 0 0)
			(layers "F.Cu" "F.Mask" "F.Paste")
			(net "RST_SMB_SSD2_ISO_N")
		)
	)
	(footprint ""
		(layer "F.Cu")
		(at 358.013 -218.44)
		(property "Reference" "R4087"
			(at 0 0 0)
			(layer "F.SilkS")
			(hide yes)
			(effects
				(font
					(size 1.27 1.27)
				)
			)
		)
		(property "Value" ""
			(at 0 0 0)
			(layer "F.Fab")
			(effects
				(font
					(size 1.27 1.27)
				)
			)
		)
		(duplicate_pad_numbers_are_jumpers no)
		(fp_line
			(start -0.7874 -0.4064)
			(end 0.7874 -0.4064)
			(stroke
				(width 0.1524)
				(type default)
			)
			(layer "F.SilkS")
		)
		(fp_line
			(start -0.7874 0.4064)
			(end -0.7874 -0.4064)
			(stroke
				(width 0.1524)
				(type default)
			)
			(layer "F.SilkS")
		)
		(fp_line
			(start 0.7874 -0.4064)
			(end 0.7874 0.4064)
			(stroke
				(width 0.1524)
				(type default)
			)
			(layer "F.SilkS")
		)
		(fp_line
			(start 0.7874 0.4064)
			(end -0.7874 0.4064)
			(stroke
				(width 0.1524)
				(type default)
			)
			(layer "F.SilkS")
		)
		(fp_line
			(start -0.67945 -0.305054)
			(end -0.12065 -0.305054)
			(stroke
				(width 0.1)
				(type default)
			)
			(layer "F.Fab")
		)
		(fp_line
			(start -0.67945 0.3048)
			(end -0.67945 -0.305054)
			(stroke
				(width 0.1)
				(type default)
			)
			(layer "F.Fab")
		)
		(fp_line
			(start -0.12065 -0.305054)
			(end -0.12065 -0.2794)
			(stroke
				(width 0.1)
				(type default)
			)
			(layer "F.Fab")
		)
		(fp_line
			(start -0.12065 -0.2794)
			(end 0.12065 -0.2794)
			(stroke
				(width 0.1)
				(type default)
			)
			(layer "F.Fab")
		)
		(fp_line
			(start -0.12065 0.2794)
			(end -0.12065 0.3048)
			(stroke
				(width 0.1)
				(type default)
			)
			(layer "F.Fab")
		)
		(fp_line
			(start -0.12065 0.3048)
			(end -0.67945 0.3048)
			(stroke
				(width 0.1)
				(type default)
			)
			(layer "F.Fab")
		)
		(fp_line
			(start 0.120396 0.2794)
			(end -0.12065 0.2794)
			(stroke
				(width 0.1)
				(type default)
			)
			(layer "F.Fab")
		)
		(fp_line
			(start 0.120396 0.3048)
			(end 0.120396 0.2794)
			(stroke
				(width 0.1)
				(type default)
			)
			(layer "F.Fab")
		)
		(fp_line
			(start 0.12065 -0.3048)
			(end 0.67945 -0.3048)
			(stroke
				(width 0.1)
				(type default)
			)
			(layer "F.Fab")
		)
		(fp_line
			(start 0.12065 -0.2794)
			(end 0.12065 -0.3048)
			(stroke
				(width 0.1)
				(type default)
			)
			(layer "F.Fab")
		)
		(fp_line
			(start 0.67945 -0.3048)
			(end 0.67945 0.3048)
			(stroke
				(width 0.1)
				(type default)
			)
			(layer "F.Fab")
		)
		(fp_line
			(start 0.67945 0.3048)
			(end 0.120396 0.3048)
			(stroke
				(width 0.1)
				(type default)
			)
			(layer "F.Fab")
		)
		(pad "1" smd circle
			(at -0.40005 0)
			(size 0 0)
			(layers "F.Cu" "F.Mask" "F.Paste")
			(net "NIC6_CLK_EN_N")
		)
		(pad "2" smd circle
			(at 0.40005 0)
			(size 0 0)
			(layers "F.Cu" "F.Mask" "F.Paste")
			(net "NIC6_CLK_EN_R_N")
		)
	)
	(footprint ""
		(layer "F.Cu")
		(at 112.311942 -110.515654)
		(property "Reference" "PC616"
			(at 0 0 0)
			(layer "F.SilkS")
			(hide yes)
			(effects
				(font
					(size 1.27 1.27)
				)
			)
		)
		(property "Value" ""
			(at 0 0 0)
			(layer "F.Fab")
			(effects
				(font
					(size 1.27 1.27)
				)
			)
		)
		(duplicate_pad_numbers_are_jumpers no)
		(fp_line
			(start -0.7874 -0.4064)
			(end 0.7874 -0.4064)
			(stroke
				(width 0.1524)
				(type default)
			)
			(layer "F.SilkS")
		)
		(fp_line
			(start -0.7874 0.4064)
			(end -0.7874 -0.4064)
			(stroke
				(width 0.1524)
				(type default)
			)
			(layer "F.SilkS")
		)
		(fp_line
			(start 0.7874 -0.4064)
			(end 0.7874 0.4064)
			(stroke
				(width 0.1524)
				(type default)
			)
			(layer "F.SilkS")
		)
		(fp_line
			(start 0.7874 0.4064)
			(end -0.7874 0.4064)
			(stroke
				(width 0.1524)
				(type default)
			)
			(layer "F.SilkS")
		)
		(fp_line
			(start -0.67945 -0.305054)
			(end -0.12065 -0.305054)
			(stroke
				(width 0.1)
				(type default)
			)
			(layer "F.Fab")
		)
		(fp_line
			(start -0.67945 0.3048)
			(end -0.67945 -0.305054)
			(stroke
				(width 0.1)
				(type default)
			)
			(layer "F.Fab")
		)
		(fp_line
			(start -0.12065 -0.305054)
			(end -0.12065 -0.2794)
			(stroke
				(width 0.1)
				(type default)
			)
			(layer "F.Fab")
		)
		(fp_line
			(start -0.12065 -0.2794)
			(end 0.12065 -0.2794)
			(stroke
				(width 0.1)
				(type default)
			)
			(layer "F.Fab")
		)
		(fp_line
			(start -0.12065 0.2794)
			(end -0.12065 0.3048)
			(stroke
				(width 0.1)
				(type default)
			)
			(layer "F.Fab")
		)
		(fp_line
			(start -0.12065 0.3048)
			(end -0.67945 0.3048)
			(stroke
				(width 0.1)
				(type default)
			)
			(layer "F.Fab")
		)
		(fp_line
			(start 0.120396 0.2794)
			(end -0.12065 0.2794)
			(stroke
				(width 0.1)
				(type default)
			)
			(layer "F.Fab")
		)
		(fp_line
			(start 0.120396 0.3048)
			(end 0.120396 0.2794)
			(stroke
				(width 0.1)
				(type default)
			)
			(layer "F.Fab")
		)
		(fp_line
			(start 0.12065 -0.3048)
			(end 0.67945 -0.3048)
			(stroke
				(width 0.1)
				(type default)
			)
			(layer "F.Fab")
		)
		(fp_line
			(start 0.12065 -0.2794)
			(end 0.12065 -0.3048)
			(stroke
				(width 0.1)
				(type default)
			)
			(layer "F.Fab")
		)
		(fp_line
			(start 0.67945 -0.3048)
			(end 0.67945 0.3048)
			(stroke
				(width 0.1)
				(type default)
			)
			(layer "F.Fab")
		)
		(fp_line
			(start 0.67945 0.3048)
			(end 0.120396 0.3048)
			(stroke
				(width 0.1)
				(type default)
			)
			(layer "F.Fab")
		)
		(pad "1" smd circle
			(at -0.40005 0)
			(size 0 0)
			(layers "F.Cu" "F.Mask" "F.Paste")
			(net "P12V_NIC1_CO_TIMER")
		)
		(pad "2" smd circle
			(at 0.40005 0)
			(size 0 0)
			(layers "F.Cu" "F.Mask" "F.Paste")
			(net "GND")
		)
	)
	(footprint ""
		(layer "F.Cu")
		(at 220.710506 -18.61439 90)
		(property "Reference" "U133"
			(at -1.44399 2.302764 90)
			(unlocked yes)
			(layer "F.SilkS")
			(effects
				(font
					(size 0.7874 0.5842)
					(thickness 0.1524)
				)
				(justify left)
			)
		)
		(property "Value" ""
			(at 0 0 90)
			(layer "F.Fab")
			(effects
				(font
					(size 1.27 1.27)
				)
			)
		)
		(duplicate_pad_numbers_are_jumpers no)
		(fp_line
			(start 1.463548 -1.549908)
			(end 1.463548 1.549908)
			(stroke
				(width 0.1524)
				(type default)
			)
			(layer "F.SilkS")
		)
		(fp_line
			(start 0.762 -1.549908)
			(end 1.463548 -1.549908)
			(stroke
				(width 0.1524)
				(type default)
			)
			(layer "F.SilkS")
		)
		(fp_line
			(start -0.787908 -1.549908)
			(end 0 -0.762)
			(stroke
				(width 0.1524)
				(type default)
			)
			(layer "F.SilkS")
		)
		(fp_line
			(start -1.463548 -1.549908)
			(end -0.787908 -1.549908)
			(stroke
				(width 0.1524)
				(type default)
			)
			(layer "F.SilkS")
		)
		(fp_line
			(start 0 -0.762)
			(end 0.762 -1.549908)
			(stroke
				(width 0.1524)
				(type default)
			)
			(layer "F.SilkS")
		)
		(fp_line
			(start 1.463548 1.549908)
			(end -1.463548 1.549908)
			(stroke
				(width 0.1524)
				(type default)
			)
			(layer "F.SilkS")
		)
		(fp_line
			(start -1.463548 1.549908)
			(end -1.463548 -1.549908)
			(stroke
				(width 0.1524)
				(type default)
			)
			(layer "F.SilkS")
		)
		(fp_poly
			(pts
				(xy -3.4798 -1.359916) (xy -2.86004 -1.050036) (xy -3.4798 -0.740156)
			)
			(stroke
				(width 0)
				(type default)
			)
			(fill yes)
			(layer "F.SilkS")
		)
		(fp_line
			(start 1.549908 -1.549908)
			(end 1.549908 1.549908)
			(stroke
				(width 0.1)
				(type default)
			)
			(layer "F.Fab")
		)
		(fp_line
			(start -1.549908 -1.549908)
			(end 1.549908 -1.549908)
			(stroke
				(width 0.1)
				(type default)
			)
			(layer "F.Fab")
		)
		(fp_line
			(start 1.549908 1.549908)
			(end -1.549908 1.549908)
			(stroke
				(width 0.1)
				(type default)
			)
			(layer "F.Fab")
		)
		(fp_line
			(start -1.549908 1.549908)
			(end -1.549908 -1.549908)
			(stroke
				(width 0.1)
				(type default)
			)
			(layer "F.Fab")
		)
		(fp_poly
			(pts
				(xy -3.4798 -1.359916) (xy -2.86004 -1.050036) (xy -3.4798 -0.740156)
			)
			(stroke
				(width 0)
				(type default)
			)
			(fill yes)
			(layer "F.Fab")
		)
		(pad "1" smd rect
			(at -2.175002 -1.050036 180)
			(size 0.6096 1.1684)
			(layers "F.Cu" "F.Mask" "F.Paste")
			(net "P3V3_SSD7")
		)
		(pad "2" smd rect
			(at -2.175002 -0.32512 180)
			(size 0.4318 1.1684)
			(layers "F.Cu" "F.Mask" "F.Paste")
			(net "SMB_ISO_SSD7_SCL")
		)
		(pad "3" smd rect
			(at -2.175002 0.32512 180)
			(size 0.4318 1.1684)
			(layers "F.Cu" "F.Mask" "F.Paste")
			(net "SMB_ISO_SSD7_SDA")
		)
		(pad "4" smd rect
			(at -2.175002 1.050036 180)
			(size 0.6096 1.1684)
			(layers "F.Cu" "F.Mask" "F.Paste")
			(net "GND")
		)
		(pad "5" smd rect
			(at 2.175002 1.050036 180)
			(size 0.6096 1.1684)
			(layers "F.Cu" "F.Mask" "F.Paste")
			(net "SMB_SSD7_ISO_EN")
		)
		(pad "6" smd rect
			(at 2.175002 0.32512 180)
			(size 0.4318 1.1684)
			(layers "F.Cu" "F.Mask" "F.Paste")
			(net "SMB_BIC_I2C9_MUX0_SSD7_R_SDA")
		)
		(pad "7" smd rect
			(at 2.175002 -0.32512 180)
			(size 0.4318 1.1684)
			(layers "F.Cu" "F.Mask" "F.Paste")
			(net "SMB_BIC_I2C9_MUX0_SSD7_R_SCL")
		)
		(pad "8" smd rect
			(at 2.175002 -1.050036 180)
			(size 0.6096 1.1684)
			(layers "F.Cu" "F.Mask" "F.Paste")
			(net "P3V3_AUX")
		)
	)
)
